(kicad_pcb
	(version 20260206)
	(generator "pcbnew")
	(generator_version "10.0")
	(general
		(thickness 1.6)
		(legacy_teardrops no)
	)
	(paper "A4")
	(title_block
		(title "12092022_DA0F0TFB6D0_F0T_FAN_BOARD_MP5048_D_brd_v02_OCP.brd")
		(comment 1 "Grand Teton / footprints 291-296 of 924")
	)
	(layers
		(0 "F.Cu" signal "TOP")
		(4 "In1.Cu" signal "GND")
		(6 "In2.Cu" signal "IN1")
		(8 "In3.Cu" signal "IN2")
		(10 "In4.Cu" signal "GND1")
		(2 "B.Cu" signal "BOTTOM")
		(9 "F.Adhes" user "F.Adhesive")
		(11 "B.Adhes" user "B.Adhesive")
		(13 "F.Paste" user "Package Geometry/Pastemask Top")
		(15 "B.Paste" user "Package Geometry/Pastemask Bottom")
		(5 "F.SilkS" user "Ref Des/Silkscreen Top")
		(7 "B.SilkS" user "Ref Des/Silkscreen Bottom")
		(1 "F.Mask" user "Board Geometry/Soldermask Top")
		(3 "B.Mask" user "Board Geometry/Soldermask Bottom")
		(17 "Dwgs.User" user "User.Drawings")
		(19 "Cmts.User" user "User.Comments")
		(21 "Eco1.User" user "User.Eco1")
		(23 "Eco2.User" user "User.Eco2")
		(25 "Edge.Cuts" user "Board Geometry/Outline")
		(27 "Margin" user)
		(31 "F.CrtYd" user "Package Geometry/Place Bound Top")
		(29 "B.CrtYd" user "Package Geometry/Place Bound Bottom")
		(35 "F.Fab" user "Ref Des/Assembly Top")
		(33 "B.Fab" user "Ref Des/Assembly Bottom")
	)
	(footprint ""
		(layer "F.Cu")
		(at 31.496 -176.403)
		(property "Reference" "R5103"
			(at 0 0 0)
			(layer "F.SilkS")
			(hide yes)
			(effects
				(font
					(size 1.27 1.27)
				)
			)
		)
		(property "Value" ""
			(at 0 0 0)
			(layer "F.Fab")
			(effects
				(font
					(size 1.27 1.27)
				)
			)
		)
		(duplicate_pad_numbers_are_jumpers no)
		(fp_line
			(start -0.7874 -0.4064)
			(end 0.7874 -0.4064)
			(stroke
				(width 0.1524)
				(type default)
			)
			(layer "F.SilkS")
		)
		(fp_line
			(start -0.7874 0.4064)
			(end -0.7874 -0.4064)
			(stroke
				(width 0.1524)
				(type default)
			)
			(layer "F.SilkS")
		)
		(fp_line
			(start 0.7874 -0.4064)
			(end 0.7874 0.4064)
			(stroke
				(width 0.1524)
				(type default)
			)
			(layer "F.SilkS")
		)
		(fp_line
			(start 0.7874 0.4064)
			(end -0.7874 0.4064)
			(stroke
				(width 0.1524)
				(type default)
			)
			(layer "F.SilkS")
		)
		(fp_line
			(start -0.67945 -0.305054)
			(end -0.12065 -0.305054)
			(stroke
				(width 0.1)
				(type default)
			)
			(layer "F.Fab")
		)
		(fp_line
			(start -0.67945 0.3048)
			(end -0.67945 -0.305054)
			(stroke
				(width 0.1)
				(type default)
			)
			(layer "F.Fab")
		)
		(fp_line
			(start -0.12065 -0.305054)
			(end -0.12065 -0.2794)
			(stroke
				(width 0.1)
				(type default)
			)
			(layer "F.Fab")
		)
		(fp_line
			(start -0.12065 -0.2794)
			(end 0.12065 -0.2794)
			(stroke
				(width 0.1)
				(type default)
			)
			(layer "F.Fab")
		)
		(fp_line
			(start -0.12065 0.2794)
			(end -0.12065 0.3048)
			(stroke
				(width 0.1)
				(type default)
			)
			(layer "F.Fab")
		)
		(fp_line
			(start -0.12065 0.3048)
			(end -0.67945 0.3048)
			(stroke
				(width 0.1)
				(type default)
			)
			(layer "F.Fab")
		)
		(fp_line
			(start 0.120396 0.2794)
			(end -0.12065 0.2794)
			(stroke
				(width 0.1)
				(type default)
			)
			(layer "F.Fab")
		)
		(fp_line
			(start 0.120396 0.3048)
			(end 0.120396 0.2794)
			(stroke
				(width 0.1)
				(type default)
			)
			(layer "F.Fab")
		)
		(fp_line
			(start 0.12065 -0.3048)
			(end 0.67945 -0.3048)
			(stroke
				(width 0.1)
				(type default)
			)
			(layer "F.Fab")
		)
		(fp_line
			(start 0.12065 -0.2794)
			(end 0.12065 -0.3048)
			(stroke
				(width 0.1)
				(type default)
			)
			(layer "F.Fab")
		)
		(fp_line
			(start 0.67945 -0.3048)
			(end 0.67945 0.3048)
			(stroke
				(width 0.1)
				(type default)
			)
			(layer "F.Fab")
		)
		(fp_line
			(start 0.67945 0.3048)
			(end 0.120396 0.3048)
			(stroke
				(width 0.1)
				(type default)
			)
			(layer "F.Fab")
		)
		(pad "1" smd circle
			(at -0.40005 0)
			(size 0 0)
			(layers "F.Cu" "F.Mask" "F.Paste")
			(net "FAN_4_FAIL_LED")
		)
		(pad "2" smd circle
			(at 0.40005 0)
			(size 0 0)
			(layers "F.Cu" "F.Mask" "F.Paste")
			(net "FAN_4_FAIL_R_LED")
		)
	)
	(footprint ""
		(layer "F.Cu")
		(at 5.969 -249.301)
		(property "Reference" "PR67"
			(at 0 0 0)
			(layer "F.SilkS")
			(hide yes)
			(effects
				(font
					(size 1.27 1.27)
				)
			)
		)
		(property "Value" ""
			(at 0 0 0)
			(layer "F.Fab")
			(effects
				(font
					(size 1.27 1.27)
				)
			)
		)
		(duplicate_pad_numbers_are_jumpers no)
		(fp_line
			(start -0.7874 -0.4064)
			(end 0.7874 -0.4064)
			(stroke
				(width 0.1524)
				(type default)
			)
			(layer "F.SilkS")
		)
		(fp_line
			(start -0.7874 0.4064)
			(end -0.7874 -0.4064)
			(stroke
				(width 0.1524)
				(type default)
			)
			(layer "F.SilkS")
		)
		(fp_line
			(start 0.7874 -0.4064)
			(end 0.7874 0.4064)
			(stroke
				(width 0.1524)
				(type default)
			)
			(layer "F.SilkS")
		)
		(fp_line
			(start 0.7874 0.4064)
			(end -0.7874 0.4064)
			(stroke
				(width 0.1524)
				(type default)
			)
			(layer "F.SilkS")
		)
		(fp_line
			(start -0.67945 -0.305054)
			(end -0.12065 -0.305054)
			(stroke
				(width 0.1)
				(type default)
			)
			(layer "F.Fab")
		)
		(fp_line
			(start -0.67945 0.3048)
			(end -0.67945 -0.305054)
			(stroke
				(width 0.1)
				(type default)
			)
			(layer "F.Fab")
		)
		(fp_line
			(start -0.12065 -0.305054)
			(end -0.12065 -0.2794)
			(stroke
				(width 0.1)
				(type default)
			)
			(layer "F.Fab")
		)
		(fp_line
			(start -0.12065 -0.2794)
			(end 0.12065 -0.2794)
			(stroke
				(width 0.1)
				(type default)
			)
			(layer "F.Fab")
		)
		(fp_line
			(start -0.12065 0.2794)
			(end -0.12065 0.3048)
			(stroke
				(width 0.1)
				(type default)
			)
			(layer "F.Fab")
		)
		(fp_line
			(start -0.12065 0.3048)
			(end -0.67945 0.3048)
			(stroke
				(width 0.1)
				(type default)
			)
			(layer "F.Fab")
		)
		(fp_line
			(start 0.120396 0.2794)
			(end -0.12065 0.2794)
			(stroke
				(width 0.1)
				(type default)
			)
			(layer "F.Fab")
		)
		(fp_line
			(start 0.120396 0.3048)
			(end 0.120396 0.2794)
			(stroke
				(width 0.1)
				(type default)
			)
			(layer "F.Fab")
		)
		(fp_line
			(start 0.12065 -0.3048)
			(end 0.67945 -0.3048)
			(stroke
				(width 0.1)
				(type default)
			)
			(layer "F.Fab")
		)
		(fp_line
			(start 0.12065 -0.2794)
			(end 0.12065 -0.3048)
			(stroke
				(width 0.1)
				(type default)
			)
			(layer "F.Fab")
		)
		(fp_line
			(start 0.67945 -0.3048)
			(end 0.67945 0.3048)
			(stroke
				(width 0.1)
				(type default)
			)
			(layer "F.Fab")
		)
		(fp_line
			(start 0.67945 0.3048)
			(end 0.120396 0.3048)
			(stroke
				(width 0.1)
				(type default)
			)
			(layer "F.Fab")
		)
		(pad "1" smd circle
			(at -0.40005 0)
			(size 0 0)
			(layers "F.Cu" "F.Mask" "F.Paste")
			(net "FAN_6_MODE")
		)
		(pad "2" smd circle
			(at 0.40005 0)
			(size 0 0)
			(layers "F.Cu" "F.Mask" "F.Paste")
			(net "GND")
		)
	)
	(footprint ""
		(layer "F.Cu")
		(at 30.099 -287.02 -90)
		(property "Reference" "C2093"
			(at 0 0 270)
			(layer "F.SilkS")
			(hide yes)
			(effects
				(font
					(size 1.27 1.27)
				)
			)
		)
		(property "Value" ""
			(at 0 0 270)
			(layer "F.Fab")
			(effects
				(font
					(size 1.27 1.27)
				)
			)
		)
		(duplicate_pad_numbers_are_jumpers no)
		(fp_line
			(start -0.7874 0.4064)
			(end -0.7874 -0.4064)
			(stroke
				(width 0.1524)
				(type default)
			)
			(layer "F.SilkS")
		)
		(fp_line
			(start 0.7874 0.4064)
			(end -0.7874 0.4064)
			(stroke
				(width 0.1524)
				(type default)
			)
			(layer "F.SilkS")
		)
		(fp_line
			(start -0.7874 -0.4064)
			(end 0.7874 -0.4064)
			(stroke
				(width 0.1524)
				(type default)
			)
			(layer "F.SilkS")
		)
		(fp_line
			(start 0.7874 -0.4064)
			(end 0.7874 0.4064)
			(stroke
				(width 0.1524)
				(type default)
			)
			(layer "F.SilkS")
		)
		(fp_line
			(start -0.67945 0.3048)
			(end -0.67945 -0.305054)
			(stroke
				(width 0.1)
				(type default)
			)
			(layer "F.Fab")
		)
		(fp_line
			(start -0.12065 0.3048)
			(end -0.67945 0.3048)
			(stroke
				(width 0.1)
				(type default)
			)
			(layer "F.Fab")
		)
		(fp_line
			(start 0.120396 0.3048)
			(end 0.120396 0.2794)
			(stroke
				(width 0.1)
				(type default)
			)
			(layer "F.Fab")
		)
		(fp_line
			(start 0.67945 0.3048)
			(end 0.120396 0.3048)
			(stroke
				(width 0.1)
				(type default)
			)
			(layer "F.Fab")
		)
		(fp_line
			(start -0.12065 0.2794)
			(end -0.12065 0.3048)
			(stroke
				(width 0.1)
				(type default)
			)
			(layer "F.Fab")
		)
		(fp_line
			(start 0.120396 0.2794)
			(end -0.12065 0.2794)
			(stroke
				(width 0.1)
				(type default)
			)
			(layer "F.Fab")
		)
		(fp_line
			(start -0.12065 -0.2794)
			(end 0.12065 -0.2794)
			(stroke
				(width 0.1)
				(type default)
			)
			(layer "F.Fab")
		)
		(fp_line
			(start 0.12065 -0.2794)
			(end 0.12065 -0.3048)
			(stroke
				(width 0.1)
				(type default)
			)
			(layer "F.Fab")
		)
		(fp_line
			(start 0.12065 -0.3048)
			(end 0.67945 -0.3048)
			(stroke
				(width 0.1)
				(type default)
			)
			(layer "F.Fab")
		)
		(fp_line
			(start 0.67945 -0.3048)
			(end 0.67945 0.3048)
			(stroke
				(width 0.1)
				(type default)
			)
			(layer "F.Fab")
		)
		(fp_line
			(start -0.67945 -0.305054)
			(end -0.12065 -0.305054)
			(stroke
				(width 0.1)
				(type default)
			)
			(layer "F.Fab")
		)
		(fp_line
			(start -0.12065 -0.305054)
			(end -0.12065 -0.2794)
			(stroke
				(width 0.1)
				(type default)
			)
			(layer "F.Fab")
		)
		(pad "1" smd circle
			(at -0.40005 0 270)
			(size 0 0)
			(layers "F.Cu" "F.Mask" "F.Paste")
			(net "P3V3_AUX")
		)
		(pad "2" smd circle
			(at 0.40005 0 270)
			(size 0 0)
			(layers "F.Cu" "F.Mask" "F.Paste")
			(net "GND")
		)
	)
	(footprint ""
		(layer "F.Cu")
		(at 19.177 -215.392 -90)
		(property "Reference" "R5660"
			(at 0 0 270)
			(layer "F.SilkS")
			(hide yes)
			(effects
				(font
					(size 1.27 1.27)
				)
			)
		)
		(property "Value" ""
			(at 0 0 270)
			(layer "F.Fab")
			(effects
				(font
					(size 1.27 1.27)
				)
			)
		)
		(duplicate_pad_numbers_are_jumpers no)
		(fp_line
			(start -0.7874 0.4064)
			(end -0.7874 -0.4064)
			(stroke
				(width 0.1524)
				(type default)
			)
			(layer "F.SilkS")
		)
		(fp_line
			(start 0.7874 0.4064)
			(end -0.7874 0.4064)
			(stroke
				(width 0.1524)
				(type default)
			)
			(layer "F.SilkS")
		)
		(fp_line
			(start -0.7874 -0.4064)
			(end 0.7874 -0.4064)
			(stroke
				(width 0.1524)
				(type default)
			)
			(layer "F.SilkS")
		)
		(fp_line
			(start 0.7874 -0.4064)
			(end 0.7874 0.4064)
			(stroke
				(width 0.1524)
				(type default)
			)
			(layer "F.SilkS")
		)
		(fp_line
			(start -0.67945 0.3048)
			(end -0.67945 -0.305054)
			(stroke
				(width 0.1)
				(type default)
			)
			(layer "F.Fab")
		)
		(fp_line
			(start -0.12065 0.3048)
			(end -0.67945 0.3048)
			(stroke
				(width 0.1)
				(type default)
			)
			(layer "F.Fab")
		)
		(fp_line
			(start 0.120396 0.3048)
			(end 0.120396 0.2794)
			(stroke
				(width 0.1)
				(type default)
			)
			(layer "F.Fab")
		)
		(fp_line
			(start 0.67945 0.3048)
			(end 0.120396 0.3048)
			(stroke
				(width 0.1)
				(type default)
			)
			(layer "F.Fab")
		)
		(fp_line
			(start -0.12065 0.2794)
			(end -0.12065 0.3048)
			(stroke
				(width 0.1)
				(type default)
			)
			(layer "F.Fab")
		)
		(fp_line
			(start 0.120396 0.2794)
			(end -0.12065 0.2794)
			(stroke
				(width 0.1)
				(type default)
			)
			(layer "F.Fab")
		)
		(fp_line
			(start -0.12065 -0.2794)
			(end 0.12065 -0.2794)
			(stroke
				(width 0.1)
				(type default)
			)
			(layer "F.Fab")
		)
		(fp_line
			(start 0.12065 -0.2794)
			(end 0.12065 -0.3048)
			(stroke
				(width 0.1)
				(type default)
			)
			(layer "F.Fab")
		)
		(fp_line
			(start 0.12065 -0.3048)
			(end 0.67945 -0.3048)
			(stroke
				(width 0.1)
				(type default)
			)
			(layer "F.Fab")
		)
		(fp_line
			(start 0.67945 -0.3048)
			(end 0.67945 0.3048)
			(stroke
				(width 0.1)
				(type default)
			)
			(layer "F.Fab")
		)
		(fp_line
			(start -0.67945 -0.305054)
			(end -0.12065 -0.305054)
			(stroke
				(width 0.1)
				(type default)
			)
			(layer "F.Fab")
		)
		(fp_line
			(start -0.12065 -0.305054)
			(end -0.12065 -0.2794)
			(stroke
				(width 0.1)
				(type default)
			)
			(layer "F.Fab")
		)
		(pad "1" smd rect
			(at -0.40005 0 90)
			(size 0.4572 0.508)
			(layers "F.Cu" "F.Mask" "F.Paste")
			(net "P12V_LED")
		)
		(pad "2" smd rect
			(at 0.40005 0 90)
			(size 0.4572 0.508)
			(layers "F.Cu" "F.Mask" "F.Paste")
			(net "U411_D1")
		)
	)
	(footprint ""
		(layer "F.Cu")
		(at 18.669 -302.514 180)
		(property "Reference" "R5321"
			(at 0 0 180)
			(layer "F.SilkS")
			(hide yes)
			(effects
				(font
					(size 1.27 1.27)
				)
			)
		)
		(property "Value" ""
			(at 0 0 180)
			(layer "F.Fab")
			(effects
				(font
					(size 1.27 1.27)
				)
			)
		)
		(duplicate_pad_numbers_are_jumpers no)
		(fp_line
			(start 1.2954 0.5842)
			(end -1.2954 0.5842)
			(stroke
				(width 0.1524)
				(type default)
			)
			(layer "F.SilkS")
		)
		(fp_line
			(start 1.2954 -0.5842)
			(end 1.2954 0.5842)
			(stroke
				(width 0.1524)
				(type default)
			)
			(layer "F.SilkS")
		)
		(fp_line
			(start -1.2954 0.5842)
			(end -1.2954 -0.5842)
			(stroke
				(width 0.1524)
				(type default)
			)
			(layer "F.SilkS")
		)
		(fp_line
			(start -1.2954 -0.5842)
			(end 1.2954 -0.5842)
			(stroke
				(width 0.1524)
				(type default)
			)
			(layer "F.SilkS")
		)
		(fp_line
			(start 1.1938 0.4064)
			(end 0.8636 0.4064)
			(stroke
				(width 0.1)
				(type default)
			)
			(layer "F.Fab")
		)
		(fp_line
			(start 1.1938 -0.406654)
			(end 1.1938 0.4064)
			(stroke
				(width 0.1)
				(type default)
			)
			(layer "F.Fab")
		)
		(fp_line
			(start 0.8636 0.4572)
			(end -0.8636 0.4572)
			(stroke
				(width 0.1)
				(type default)
			)
			(layer "F.Fab")
		)
		(fp_line
			(start 0.8636 0.4064)
			(end 0.8636 0.4572)
			(stroke
				(width 0.1)
				(type default)
			)
			(layer "F.Fab")
		)
		(fp_line
			(start 0.8636 -0.406654)
			(end 1.1938 -0.406654)
			(stroke
				(width 0.1)
				(type default)
			)
			(layer "F.Fab")
		)
		(fp_line
			(start 0.8636 -0.4572)
			(end 0.8636 -0.406654)
			(stroke
				(width 0.1)
				(type default)
			)
			(layer "F.Fab")
		)
		(fp_line
			(start -0.8636 0.4572)
			(end -0.8636 0.4318)
			(stroke
				(width 0.1)
				(type default)
			)
			(layer "F.Fab")
		)
		(fp_line
			(start -0.8636 0.4318)
			(end -0.8636 0.4064)
			(stroke
				(width 0.1)
				(type default)
			)
			(layer "F.Fab")
		)
		(fp_line
			(start -0.8636 0.4064)
			(end -1.1938 0.4064)
			(stroke
				(width 0.1)
				(type default)
			)
			(layer "F.Fab")
		)
		(fp_line
			(start -0.8636 -0.406654)
			(end -0.8636 -0.4572)
			(stroke
				(width 0.1)
				(type default)
			)
			(layer "F.Fab")
		)
		(fp_line
			(start -0.8636 -0.4572)
			(end 0.8636 -0.4572)
			(stroke
				(width 0.1)
				(type default)
			)
			(layer "F.Fab")
		)
		(fp_line
			(start -1.1938 0.4064)
			(end -1.1938 -0.406654)
			(stroke
				(width 0.1)
				(type default)
			)
			(layer "F.Fab")
		)
		(fp_line
			(start -1.1938 -0.406654)
			(end -0.8636 -0.406654)
			(stroke
				(width 0.1)
				(type default)
			)
			(layer "F.Fab")
		)
		(pad "1" smd rect
			(at -0.7366 0 90)
			(size 0.7112 0.8128)
			(layers "F.Cu" "F.Mask" "F.Paste")
			(net "P52V_FAN_7")
		)
		(pad "2" smd rect
			(at 0.7366 0 90)
			(size 0.7112 0.8128)
			(layers "F.Cu" "F.Mask" "F.Paste")
			(net "FAN_7_TACH_OL_R")
		)
	)
	(footprint ""
		(layer "F.Cu")
		(at 16.139922 -91.0082)
		(property "Reference" "PC42"
			(at -5.344922 5.94487 0)
			(unlocked yes)
			(layer "F.SilkS")
			(effects
				(font
					(size 0.7874 0.5842)
					(thickness 0.1524)
				)
				(justify left)
			)
		)
		(property "Value" ""
			(at 0 0 0)
			(layer "F.Fab")
			(effects
				(font
					(size 1.27 1.27)
				)
			)
		)
		(duplicate_pad_numbers_are_jumpers no)
		(fp_line
			(start -5.249926 -3.979926)
			(end -5.249926 -1.2446)
			(stroke
				(width 0.1524)
				(type default)
			)
			(layer "F.SilkS")
		)
		(fp_line
			(start -5.249926 1.2446)
			(end -5.249926 3.979926)
			(stroke
				(width 0.1524)
				(type default)
			)
			(layer "F.SilkS")
		)
		(fp_line
			(start -5.249926 3.979926)
			(end -3.979926 5.249926)
			(stroke
				(width 0.1524)
				(type default)
			)
			(layer "F.SilkS")
		)
		(fp_line
			(start -3.979926 -5.249926)
			(end -5.249926 -3.979926)
			(stroke
				(width 0.1524)
				(type default)
			)
			(layer "F.SilkS")
		)
		(fp_line
			(start -3.979926 5.249926)
			(end 5.249926 5.249926)
			(stroke
				(width 0.1524)
				(type default)
			)
			(layer "F.SilkS")
		)
		(fp_line
			(start 5.249926 -5.249926)
			(end -3.979926 -5.249926)
			(stroke
				(width 0.1524)
				(type default)
			)
			(layer "F.SilkS")
		)
		(fp_line
			(start 5.249926 -1.2446)
			(end 5.249926 -5.249926)
			(stroke
				(width 0.1524)
				(type default)
			)
			(layer "F.SilkS")
		)
		(fp_line
			(start 5.249926 5.249926)
			(end 5.249926 1.2446)
			(stroke
				(width 0.1524)
				(type default)
			)
			(layer "F.SilkS")
		)
		(fp_line
			(start -5.249926 -5.249926)
			(end -5.249926 5.249926)
			(stroke
				(width 0.1)
				(type default)
			)
			(layer "F.Fab")
		)
		(fp_line
			(start -5.249926 5.249926)
			(end 5.249926 5.249926)
			(stroke
				(width 0.1)
				(type default)
			)
			(layer "F.Fab")
		)
		(fp_line
			(start 5.249926 -5.249926)
			(end -5.249926 -5.249926)
			(stroke
				(width 0.1)
				(type default)
			)
			(layer "F.Fab")
		)
		(fp_line
			(start 5.249926 5.249926)
			(end 5.249926 -5.249926)
			(stroke
				(width 0.1)
				(type default)
			)
			(layer "F.Fab")
		)
		(pad "1" smd rect
			(at -4.45008 0 90)
			(size 2.2098 4.4196)
			(layers "F.Cu" "F.Mask" "F.Paste")
			(net "P52V_FAN_5")
		)
		(pad "2" smd rect
			(at 4.45008 0 90)
			(size 2.2098 4.4196)
			(layers "F.Cu" "F.Mask" "F.Paste")
			(net "GND")
		)
	)
)
